# SCM (Grand Teton) — schematic netlist excerpt (pin names and nets, part order shuffled) for the footprints in the layout excerpt that follows; sources: Cadence DE-HDL packaged netlist, KiCad conversion of 12092022_DA0F0TMDCD0_F0T_Management_Board_D_brd_V3_OCP.brd

R466  Q_RES  33.2 1% CHIP  pkg 0402LF  page 13 : A = FLASH_WP_STATUS_R1 ; B = FLASH_WP_STATUS
D21  Q_LED  IC  pkg THLF  page 50 : A = LED_D21_R3 ; C = GND

(kicad_pcb
	(version 20260206)
	(generator "pcbnew")
	(generator_version "10.0")
	(general
		(thickness 1.6)
		(legacy_teardrops no)
	)
	(paper "A4")
	(title_block
		(title "12092022_DA0F0TMDCD0_F0T_Management_Board_D_brd_V3_OCP.brd")
		(comment 1 "Grand Teton / footprints 349-350 of 1440")
	)
	(layers
		(0 "F.Cu" signal "TOP")
		(4 "In1.Cu" signal "GND")
		(6 "In2.Cu" signal "IN1")
		(8 "In3.Cu" signal "GND1")
		(10 "In4.Cu" signal "IN2")
		(12 "In5.Cu" signal "VCC")
		(14 "In6.Cu" signal "VCC1")
		(16 "In7.Cu" signal "IN3")
		(18 "In8.Cu" signal "GND2")
		(20 "In9.Cu" signal "IN4")
		(22 "In10.Cu" signal "GND3")
		(2 "B.Cu" signal "BOTTOM")
		(9 "F.Adhes" user "F.Adhesive")
		(11 "B.Adhes" user "B.Adhesive")
		(13 "F.Paste" user "Package Geometry/Pastemask Top")
		(15 "B.Paste" user "Package Geometry/Pastemask Bottom")
		(5 "F.SilkS" user "Ref Des/Silkscreen Top")
		(7 "B.SilkS" user "Ref Des/Silkscreen Bottom")
		(1 "F.Mask" user "Board Geometry/Soldermask Top")
		(3 "B.Mask" user "Board Geometry/Soldermask Bottom")
		(17 "Dwgs.User" user "User.Drawings")
		(19 "Cmts.User" user "User.Comments")
		(21 "Eco1.User" user "User.Eco1")
		(23 "Eco2.User" user "User.Eco2")
		(25 "Edge.Cuts" user "Board Geometry/Outline")
		(27 "Margin" user)
		(31 "F.CrtYd" user "Package Geometry/Place Bound Top")
		(29 "B.CrtYd" user "Package Geometry/Place Bound Bottom")
		(35 "F.Fab" user "Ref Des/Assembly Top")
		(33 "B.Fab" user "Ref Des/Assembly Bottom")
	)
	(footprint ""
		(layer "F.Cu")
		(at 53.630068 -6.290056)
		(property "Reference" "D21"
			(at -1.143 -2.708148 0)
			(unlocked yes)
			(layer "F.SilkS")
			(effects
				(font
					(size 0.7874 0.5842)
					(thickness 0.1524)
				)
				(justify left)
			)
		)
		(property "Value" ""
			(at 0 0 0)
			(layer "F.Fab")
			(effects
				(font
					(size 1.27 1.27)
				)
			)
		)
		(duplicate_pad_numbers_are_jumpers no)
		(fp_line
			(start -1.080008 -1.999996)
			(end 3.620008 -1.999996)
			(stroke
				(width 0.1524)
				(type default)
			)
			(layer "F.SilkS")
		)
		(fp_line
			(start -1.080008 3.999992)
			(end -1.080008 -1.999996)
			(stroke
				(width 0.1524)
				(type default)
			)
			(layer "F.SilkS")
		)
		(fp_line
			(start -0.230124 3.999992)
			(end -1.080008 3.999992)
			(stroke
				(width 0.1524)
				(type default)
			)
			(layer "F.SilkS")
		)
		(fp_line
			(start -0.230124 5.199888)
			(end -0.230124 3.999992)
			(stroke
				(width 0.1524)
				(type default)
			)
			(layer "F.SilkS")
		)
		(fp_line
			(start 2.770124 3.999992)
			(end 2.770124 5.199888)
			(stroke
				(width 0.1524)
				(type default)
			)
			(layer "F.SilkS")
		)
		(fp_line
			(start 3.620008 -1.999996)
			(end 3.620008 3.999992)
			(stroke
				(width 0.1524)
				(type default)
			)
			(layer "F.SilkS")
		)
		(fp_line
			(start 3.620008 3.999992)
			(end 2.770124 3.999992)
			(stroke
				(width 0.1524)
				(type default)
			)
			(layer "F.SilkS")
		)
		(fp_arc
			(start 1.27 6.700012)
			(mid 0.209252 6.260636)
			(end -0.230124 5.199888)
			(stroke
				(width 0.1524)
				(type default)
			)
			(layer "F.SilkS")
		)
		(fp_arc
			(start 2.770124 5.199888)
			(mid 2.330748 6.260636)
			(end 1.27 6.700012)
			(stroke
				(width 0.1524)
				(type default)
			)
			(layer "F.SilkS")
		)
		(fp_line
			(start -1.080008 -1.999996)
			(end 3.620008 -1.999996)
			(stroke
				(width 0.1)
				(type default)
			)
			(layer "F.Fab")
		)
		(fp_line
			(start -1.080008 3.999992)
			(end -1.080008 -1.999996)
			(stroke
				(width 0.1)
				(type default)
			)
			(layer "F.Fab")
		)
		(fp_line
			(start -0.230124 3.999992)
			(end -1.080008 3.999992)
			(stroke
				(width 0.1)
				(type default)
			)
			(layer "F.Fab")
		)
		(fp_line
			(start -0.230124 5.199888)
			(end -0.230124 3.999992)
			(stroke
				(width 0.1)
				(type default)
			)
			(layer "F.Fab")
		)
		(fp_line
			(start 2.770124 3.999992)
			(end 2.770124 5.199888)
			(stroke
				(width 0.1)
				(type default)
			)
			(layer "F.Fab")
		)
		(fp_line
			(start 3.620008 -1.999996)
			(end 3.620008 3.999992)
			(stroke
				(width 0.1)
				(type default)
			)
			(layer "F.Fab")
		)
		(fp_line
			(start 3.620008 3.999992)
			(end 2.770124 3.999992)
			(stroke
				(width 0.1)
				(type default)
			)
			(layer "F.Fab")
		)
		(fp_arc
			(start 1.27 6.700012)
			(mid 0.209252 6.260636)
			(end -0.230124 5.199888)
			(stroke
				(width 0.1)
				(type default)
			)
			(layer "F.Fab")
		)
		(fp_arc
			(start 2.770124 5.199888)
			(mid 2.330748 6.260636)
			(end 1.27 6.700012)
			(stroke
				(width 0.1)
				(type default)
			)
			(layer "F.Fab")
		)
		(pad "A" thru_hole rect
			(at 0 0)
			(size 1.2192 1.2192)
			(drill 0.8128)
			(layers "*.Cu" "*.Mask")
			(remove_unused_layers no)
			(net "LED_D21_R3")
			(clearance 0.0508)
			(thermal_gap 0.0508)
			(padstack
				(mode front_inner_back)
				(layer "Inner"
					(shape circle)
					(size 1.2192 1.2192)
					(clearance 0.0508)
				)
				(layer "B.Cu"
					(shape rect)
					(size 1.2192 1.2192)
					(clearance 0.0508)
				)
			)
		)
		(pad "C" thru_hole circle
			(at 2.54 0)
			(size 1.2192 1.2192)
			(drill 0.8128)
			(layers "*.Cu" "*.Mask")
			(remove_unused_layers no)
			(net "GND")
			(clearance 0.0508)
			(thermal_gap 0.0508)
		)
	)
	(footprint ""
		(layer "F.Cu")
		(at 56.4642 -71.2724 90)
		(property "Reference" "R466"
			(at 0 0 90)
			(layer "F.SilkS")
			(hide yes)
			(effects
				(font
					(size 1.27 1.27)
				)
			)
		)
		(property "Value" ""
			(at 0 0 90)
			(layer "F.Fab")
			(effects
				(font
					(size 1.27 1.27)
				)
			)
		)
		(duplicate_pad_numbers_are_jumpers no)
		(fp_line
			(start 0.7874 -0.4064)
			(end 0.7874 0.4064)
			(stroke
				(width 0.1524)
				(type default)
			)
			(layer "F.SilkS")
		)
		(fp_line
			(start -0.7874 -0.4064)
			(end 0.7874 -0.4064)
			(stroke
				(width 0.1524)
				(type default)
			)
			(layer "F.SilkS")
		)
		(fp_line
			(start 0.7874 0.4064)
			(end -0.7874 0.4064)
			(stroke
				(width 0.1524)
				(type default)
			)
			(layer "F.SilkS")
		)
		(fp_line
			(start -0.7874 0.4064)
			(end -0.7874 -0.4064)
			(stroke
				(width 0.1524)
				(type default)
			)
			(layer "F.SilkS")
		)
		(fp_line
			(start -0.12065 -0.305054)
			(end -0.12065 -0.2794)
			(stroke
				(width 0.1)
				(type default)
			)
			(layer "F.Fab")
		)
		(fp_line
			(start -0.67945 -0.305054)
			(end -0.12065 -0.305054)
			(stroke
				(width 0.1)
				(type default)
			)
			(layer "F.Fab")
		)
		(fp_line
			(start 0.67945 -0.3048)
			(end 0.67945 0.3048)
			(stroke
				(width 0.1)
				(type default)
			)
			(layer "F.Fab")
		)
		(fp_line
			(start 0.12065 -0.3048)
			(end 0.67945 -0.3048)
			(stroke
				(width 0.1)
				(type default)
			)
			(layer "F.Fab")
		)
		(fp_line
			(start 0.12065 -0.2794)
			(end 0.12065 -0.3048)
			(stroke
				(width 0.1)
				(type default)
			)
			(layer "F.Fab")
		)
		(fp_line
			(start -0.12065 -0.2794)
			(end 0.12065 -0.2794)
			(stroke
				(width 0.1)
				(type default)
			)
			(layer "F.Fab")
		)
		(fp_line
			(start 0.120396 0.2794)
			(end -0.12065 0.2794)
			(stroke
				(width 0.1)
				(type default)
			)
			(layer "F.Fab")
		)
		(fp_line
			(start -0.12065 0.2794)
			(end -0.12065 0.3048)
			(stroke
				(width 0.1)
				(type default)
			)
			(layer "F.Fab")
		)
		(fp_line
			(start 0.67945 0.3048)
			(end 0.120396 0.3048)
			(stroke
				(width 0.1)
				(type default)
			)
			(layer "F.Fab")
		)
		(fp_line
			(start 0.120396 0.3048)
			(end 0.120396 0.2794)
			(stroke
				(width 0.1)
				(type default)
			)
			(layer "F.Fab")
		)
		(fp_line
			(start -0.12065 0.3048)
			(end -0.67945 0.3048)
			(stroke
				(width 0.1)
				(type default)
			)
			(layer "F.Fab")
		)
		(fp_line
			(start -0.67945 0.3048)
			(end -0.67945 -0.305054)
			(stroke
				(width 0.1)
				(type default)
			)
			(layer "F.Fab")
		)
		(pad "1" smd circle
			(at -0.40005 0 90)
			(size 0 0)
			(layers "F.Cu" "F.Mask" "F.Paste")
			(net "FLASH_WP_STATUS_R1")
		)
		(pad "2" smd circle
			(at 0.40005 0 90)
			(size 0 0)
			(layers "F.Cu" "F.Mask" "F.Paste")
			(net "FLASH_WP_STATUS")
		)
	)
)
